(kicad_pcb
	(version 20241229)
	(generator "pcbnew")
	(generator_version "9.0")
	(general
		(thickness 1.62)
		(legacy_teardrops no)
	)
	(paper "A3")
	(title_block
		(title "COM Express 7 Baseboard")
		(date "2025-02-04")
		(rev "1.1.2")
		(company "Antmicro Ltd")
		(comment 1 "www.antmicro.com")
		(comment 9 "footprints 746-750 of 802")
	)
	(layers
		(0 "F.Cu" signal)
		(4 "In1.Cu" signal)
		(6 "In2.Cu" signal)
		(8 "In3.Cu" signal)
		(10 "In4.Cu" signal)
		(12 "In5.Cu" signal)
		(14 "In6.Cu" signal)
		(2 "B.Cu" signal)
		(9 "F.Adhes" user "F.Adhesive")
		(11 "B.Adhes" user "B.Adhesive")
		(13 "F.Paste" user)
		(15 "B.Paste" user)
		(5 "F.SilkS" user "F.Silkscreen")
		(7 "B.SilkS" user "B.Silkscreen")
		(1 "F.Mask" user)
		(3 "B.Mask" user)
		(17 "Dwgs.User" user "User.Drawings")
		(19 "Cmts.User" user "User.Comments")
		(21 "Eco1.User" user "User.Eco1")
		(23 "Eco2.User" user "User.Eco2")
		(25 "Edge.Cuts" user)
		(27 "Margin" user)
		(31 "F.CrtYd" user "F.Courtyard")
		(29 "B.CrtYd" user "B.Courtyard")
		(35 "F.Fab" user)
		(33 "B.Fab" user)
	)
	(footprint "antmicro-footprints:C_0603_1608Metric"
		(layer "B.Cu")
		(at 148.7 87.23 180)
		(descr "Capacitor SMD 0603")
		(tags "capacitor 0603")
		(property "Reference" "C81"
			(at -3.3 -0.53 0)
			(layer "B.SilkS")
			(effects
				(font
					(size 0.7 0.7)
					(thickness 0.15)
				)
				(justify left bottom mirror)
			)
		)
		(property "Value" "C_22u_16V_0603"
			(at -1.42757 -1.770288 0)
			(layer "B.Fab")
			(effects
				(font
					(size 0.7 0.7)
					(thickness 0.15)
				)
				(justify left bottom mirror)
			)
		)
		(property "Datasheet" "https://product.samsungsem.com/mlcc/CL10A226MO7JZN.do"
			(at 0 0 180)
			(layer "F.Fab")
			(hide yes)
			(effects
				(font
					(size 1.27 1.27)
					(thickness 0.15)
				)
			)
		)
		(property "Author" "Antmicro"
			(at 297.4 174.46 0)
			(layer "B.Fab")
			(hide yes)
			(effects
				(font
					(size 1 1)
					(thickness 0.15)
				)
				(justify mirror)
			)
		)
		(property "Dielectric" ""
			(at 297.4 174.46 0)
			(layer "B.Fab")
			(hide yes)
			(effects
				(font
					(size 1 1)
					(thickness 0.15)
				)
				(justify mirror)
			)
		)
		(property "License" "Apache-2.0"
			(at 297.4 174.46 0)
			(layer "B.Fab")
			(hide yes)
			(effects
				(font
					(size 1 1)
					(thickness 0.15)
				)
				(justify mirror)
			)
		)
		(property "MPN" "CL10A226MO7JZNC"
			(at 297.4 174.46 0)
			(layer "B.Fab")
			(hide yes)
			(effects
				(font
					(size 1 1)
					(thickness 0.15)
				)
				(justify mirror)
			)
		)
		(property "Manufacturer" "Samsung Electro-Mechanics"
			(at 297.4 174.46 0)
			(layer "B.Fab")
			(hide yes)
			(effects
				(font
					(size 1 1)
					(thickness 0.15)
				)
				(justify mirror)
			)
		)
		(property "Public" "False"
			(at 297.4 174.46 0)
			(layer "B.Fab")
			(hide yes)
			(effects
				(font
					(size 1 1)
					(thickness 0.15)
				)
				(justify mirror)
			)
		)
		(property "Val" "22u"
			(at 297.4 174.46 0)
			(layer "B.Fab")
			(hide yes)
			(effects
				(font
					(size 1 1)
					(thickness 0.15)
				)
				(justify mirror)
			)
		)
		(property "Voltage" "16V"
			(at 297.4 174.46 0)
			(layer "B.Fab")
			(hide yes)
			(effects
				(font
					(size 1 1)
					(thickness 0.15)
				)
				(justify mirror)
			)
		)
		(sheetname "M.2 key E")
		(sheetfile "m2keye.kicad_sch")
		(attr smd)
		(fp_line
			(start 0.15 0.4)
			(end -0.15 0.4)
			(stroke
				(width 0.15)
				(type solid)
			)
			(layer "B.SilkS")
		)
		(fp_line
			(start 0.15 -0.4)
			(end -0.15 -0.4)
			(stroke
				(width 0.15)
				(type solid)
			)
			(layer "B.SilkS")
		)
		(fp_rect
			(start -1.25 0.65)
			(end 1.25 -0.65)
			(stroke
				(width 0.05)
				(type solid)
			)
			(fill no)
			(layer "B.CrtYd")
		)
		(fp_rect
			(start -0.8 0.4)
			(end 0.8 -0.4)
			(stroke
				(width 0.15)
				(type solid)
			)
			(fill no)
			(layer "B.Fab")
		)
		(pad "1" smd roundrect
			(at -0.7 0 180)
			(size 0.8 1)
			(layers "B.Cu" "B.Mask" "B.Paste")
			(roundrect_rratio 0.2)
			(net 1 "GND")
			(pintype "passive")
			(teardrops
				(best_length_ratio 0.2)
				(max_length 1)
				(best_width_ratio 0.9)
				(max_width 2)
				(curved_edges yes)
				(filter_ratio 0.9)
				(enabled yes)
				(allow_two_segments yes)
				(prefer_zone_connections yes)
			)
		)
		(pad "2" smd roundrect
			(at 0.7 0 180)
			(size 0.8 1)
			(layers "B.Cu" "B.Mask" "B.Paste")
			(roundrect_rratio 0.2)
			(net 2 "+3V3")
			(pintype "passive")
			(teardrops
				(best_length_ratio 0.2)
				(max_length 1)
				(best_width_ratio 0.9)
				(max_width 2)
				(curved_edges yes)
				(filter_ratio 0.9)
				(enabled yes)
				(allow_two_segments yes)
				(prefer_zone_connections yes)
			)
		)
	)
	(footprint "antmicro-footprints:C_0402_1005Metric"
		(layer "B.Cu")
		(at 146.95 133.87)
		(descr "Capacitor SMD 0402")
		(tags "capacitor SMD 0402")
		(property "Reference" "C166"
			(at -4.3 -4.91 0)
			(layer "B.SilkS")
			(effects
				(font
					(size 0.7 0.7)
					(thickness 0.15)
				)
				(justify right bottom mirror)
			)
		)
		(property "Value" "C_100n_0402"
			(at -1.022927 -2.155213 0)
			(layer "B.Fab")
			(effects
				(font
					(size 0.7 0.7)
					(thickness 0.15)
				)
				(justify right bottom mirror)
			)
		)
		(property "Datasheet" "https://www.murata.com/products/productdetail?partno=GRM155R61H104KE14%23"
			(at 0 0 0)
			(layer "F.Fab")
			(hide yes)
			(effects
				(font
					(size 1.27 1.27)
					(thickness 0.15)
				)
			)
		)
		(property "Author" "Antmicro"
			(at 0 0 0)
			(layer "B.Fab")
			(hide yes)
			(effects
				(font
					(size 1 1)
					(thickness 0.15)
				)
				(justify mirror)
			)
		)
		(property "Dielectric" "X5R"
			(at 0 0 0)
			(layer "B.Fab")
			(hide yes)
			(effects
				(font
					(size 1 1)
					(thickness 0.15)
				)
				(justify mirror)
			)
		)
		(property "License" "Apache-2.0"
			(at 0 0 0)
			(layer "B.Fab")
			(hide yes)
			(effects
				(font
					(size 1 1)
					(thickness 0.15)
				)
				(justify mirror)
			)
		)
		(property "MPN" "GRM155R61H104KE14D"
			(at 0 0 0)
			(layer "B.Fab")
			(hide yes)
			(effects
				(font
					(size 1 1)
					(thickness 0.15)
				)
				(justify mirror)
			)
		)
		(property "Manufacturer" "Murata"
			(at 0 0 0)
			(layer "B.Fab")
			(hide yes)
			(effects
				(font
					(size 1 1)
					(thickness 0.15)
				)
				(justify mirror)
			)
		)
		(property "Public" "False"
			(at 0 0 0)
			(layer "B.Fab")
			(hide yes)
			(effects
				(font
					(size 1 1)
					(thickness 0.15)
				)
				(justify mirror)
			)
		)
		(property "Val" "100n"
			(at 0 0 0)
			(layer "B.Fab")
			(hide yes)
			(effects
				(font
					(size 1 1)
					(thickness 0.15)
				)
				(justify mirror)
			)
		)
		(property "Voltage" "50V"
			(at 0 0 0)
			(layer "B.Fab")
			(hide yes)
			(effects
				(font
					(size 1 1)
					(thickness 0.15)
				)
				(justify mirror)
			)
		)
		(sheetname "KR to SFI #1")
		(sheetfile "kr_sfi.kicad_sch")
		(attr smd)
		(fp_rect
			(start -0.925 0.47)
			(end 0.925 -0.47)
			(stroke
				(width 0.05)
				(type default)
			)
			(fill no)
			(layer "B.CrtYd")
		)
		(fp_line
			(start -0.494 -0.248)
			(end 0.504 -0.248)
			(stroke
				(width 0.15)
				(type solid)
			)
			(layer "B.Fab")
		)
		(fp_line
			(start -0.494 0.25)
			(end -0.494 -0.248)
			(stroke
				(width 0.15)
				(type solid)
			)
			(layer "B.Fab")
		)
		(fp_line
			(start 0.504 -0.248)
			(end 0.504 0.25)
			(stroke
				(width 0.15)
				(type solid)
			)
			(layer "B.Fab")
		)
		(fp_line
			(start 0.504 0.25)
			(end -0.494 0.25)
			(stroke
				(width 0.15)
				(type solid)
			)
			(layer "B.Fab")
		)
		(pad "1" smd roundrect
			(at -0.48 0)
			(size 0.59 0.64)
			(layers "B.Cu" "B.Mask" "B.Paste")
			(roundrect_rratio 0.25)
			(net 1 "GND")
			(pintype "passive")
			(teardrops
				(best_length_ratio 0.2)
				(max_length 1)
				(best_width_ratio 0.9)
				(max_width 2)
				(curved_edges yes)
				(filter_ratio 0.9)
				(enabled yes)
				(allow_two_segments yes)
				(prefer_zone_connections yes)
			)
		)
		(pad "2" smd roundrect
			(at 0.48 0)
			(size 0.59 0.64)
			(layers "B.Cu" "B.Mask" "B.Paste")
			(roundrect_rratio 0.25)
			(net 78 "+1V8")
			(pintype "passive")
			(teardrops
				(best_length_ratio 0.2)
				(max_length 1)
				(best_width_ratio 0.9)
				(max_width 2)
				(curved_edges yes)
				(filter_ratio 0.9)
				(enabled yes)
				(allow_two_segments yes)
				(prefer_zone_connections yes)
			)
		)
	)
	(footprint "antmicro-footprints:C_0402_1005Metric"
		(layer "B.Cu")
		(at 137 162.76)
		(descr "Capacitor SMD 0402")
		(tags "capacitor SMD 0402")
		(property "Reference" "C25"
			(at -3.05 0.45 0)
			(layer "B.SilkS")
			(effects
				(font
					(size 0.7 0.7)
					(thickness 0.15)
				)
				(justify right bottom mirror)
			)
		)
		(property "Value" "C_100n_0402"
			(at -1.022927 -2.155213 0)
			(layer "B.Fab")
			(effects
				(font
					(size 0.7 0.7)
					(thickness 0.15)
				)
				(justify right bottom mirror)
			)
		)
		(property "Datasheet" "https://www.murata.com/products/productdetail?partno=GRM155R61H104KE14%23"
			(at 0 0 0)
			(layer "F.Fab")
			(hide yes)
			(effects
				(font
					(size 1.27 1.27)
					(thickness 0.15)
				)
			)
		)
		(property "Author" "Antmicro"
			(at 0 0 0)
			(layer "B.Fab")
			(hide yes)
			(effects
				(font
					(size 1 1)
					(thickness 0.15)
				)
				(justify mirror)
			)
		)
		(property "Dielectric" "X5R"
			(at 0 0 0)
			(layer "B.Fab")
			(hide yes)
			(effects
				(font
					(size 1 1)
					(thickness 0.15)
				)
				(justify mirror)
			)
		)
		(property "License" "Apache-2.0"
			(at 0 0 0)
			(layer "B.Fab")
			(hide yes)
			(effects
				(font
					(size 1 1)
					(thickness 0.15)
				)
				(justify mirror)
			)
		)
		(property "MPN" "GRM155R61H104KE14D"
			(at 0 0 0)
			(layer "B.Fab")
			(hide yes)
			(effects
				(font
					(size 1 1)
					(thickness 0.15)
				)
				(justify mirror)
			)
		)
		(property "Manufacturer" "Murata"
			(at 0 0 0)
			(layer "B.Fab")
			(hide yes)
			(effects
				(font
					(size 1 1)
					(thickness 0.15)
				)
				(justify mirror)
			)
		)
		(property "Public" "False"
			(at 0 0 0)
			(layer "B.Fab")
			(hide yes)
			(effects
				(font
					(size 1 1)
					(thickness 0.15)
				)
				(justify mirror)
			)
		)
		(property "Val" "100n"
			(at 0 0 0)
			(layer "B.Fab")
			(hide yes)
			(effects
				(font
					(size 1 1)
					(thickness 0.15)
				)
				(justify mirror)
			)
		)
		(property "Voltage" "50V"
			(at 0 0 0)
			(layer "B.Fab")
			(hide yes)
			(effects
				(font
					(size 1 1)
					(thickness 0.15)
				)
				(justify mirror)
			)
		)
		(sheetname "2xSFP+")
		(sheetfile "2xSFP+.kicad_sch")
		(attr smd)
		(fp_rect
			(start -0.925 0.47)
			(end 0.925 -0.47)
			(stroke
				(width 0.05)
				(type default)
			)
			(fill no)
			(layer "B.CrtYd")
		)
		(fp_line
			(start -0.494 -0.248)
			(end 0.504 -0.248)
			(stroke
				(width 0.15)
				(type solid)
			)
			(layer "B.Fab")
		)
		(fp_line
			(start -0.494 0.25)
			(end -0.494 -0.248)
			(stroke
				(width 0.15)
				(type solid)
			)
			(layer "B.Fab")
		)
		(fp_line
			(start 0.504 -0.248)
			(end 0.504 0.25)
			(stroke
				(width 0.15)
				(type solid)
			)
			(layer "B.Fab")
		)
		(fp_line
			(start 0.504 0.25)
			(end -0.494 0.25)
			(stroke
				(width 0.15)
				(type solid)
			)
			(layer "B.Fab")
		)
		(pad "1" smd roundrect
			(at -0.48 0)
			(size 0.59 0.64)
			(layers "B.Cu" "B.Mask" "B.Paste")
			(roundrect_rratio 0.25)
			(net 1 "GND")
			(pintype "passive")
			(teardrops
				(best_length_ratio 0.2)
				(max_length 1)
				(best_width_ratio 0.9)
				(max_width 2)
				(curved_edges yes)
				(filter_ratio 0.9)
				(enabled yes)
				(allow_two_segments yes)
				(prefer_zone_connections yes)
			)
		)
		(pad "2" smd roundrect
			(at 0.48 0)
			(size 0.59 0.64)
			(layers "B.Cu" "B.Mask" "B.Paste")
			(roundrect_rratio 0.25)
			(net 2 "+3V3")
			(pintype "passive")
			(teardrops
				(best_length_ratio 0.2)
				(max_length 1)
				(best_width_ratio 0.9)
				(max_width 2)
				(curved_edges yes)
				(filter_ratio 0.9)
				(enabled yes)
				(allow_two_segments yes)
				(prefer_zone_connections yes)
			)
		)
	)
	(footprint "antmicro-footprints:C_0402_1005Metric"
		(layer "B.Cu")
		(at 151.45 141.36 -90)
		(descr "Capacitor SMD 0402")
		(tags "capacitor SMD 0402")
		(property "Reference" "C168"
			(at 0.85 -0.45 90)
			(layer "B.SilkS")
			(effects
				(font
					(size 0.7 0.7)
					(thickness 0.15)
				)
				(justify left bottom mirror)
			)
		)
		(property "Value" "C_100n_0402"
			(at -1.022927 -2.155213 90)
			(layer "B.Fab")
			(effects
				(font
					(size 0.7 0.7)
					(thickness 0.15)
				)
				(justify left bottom mirror)
			)
		)
		(property "Datasheet" "https://www.murata.com/products/productdetail?partno=GRM155R61H104KE14%23"
			(at 0 0 270)
			(layer "F.Fab")
			(hide yes)
			(effects
				(font
					(size 1.27 1.27)
					(thickness 0.15)
				)
			)
		)
		(property "Author" "Antmicro"
			(at 10.09 292.81 0)
			(layer "B.Fab")
			(hide yes)
			(effects
				(font
					(size 1 1)
					(thickness 0.15)
				)
				(justify mirror)
			)
		)
		(property "Dielectric" "X5R"
			(at 10.09 292.81 0)
			(layer "B.Fab")
			(hide yes)
			(effects
				(font
					(size 1 1)
					(thickness 0.15)
				)
				(justify mirror)
			)
		)
		(property "License" "Apache-2.0"
			(at 10.09 292.81 0)
			(layer "B.Fab")
			(hide yes)
			(effects
				(font
					(size 1 1)
					(thickness 0.15)
				)
				(justify mirror)
			)
		)
		(property "MPN" "GRM155R61H104KE14D"
			(at 10.09 292.81 0)
			(layer "B.Fab")
			(hide yes)
			(effects
				(font
					(size 1 1)
					(thickness 0.15)
				)
				(justify mirror)
			)
		)
		(property "Manufacturer" "Murata"
			(at 10.09 292.81 0)
			(layer "B.Fab")
			(hide yes)
			(effects
				(font
					(size 1 1)
					(thickness 0.15)
				)
				(justify mirror)
			)
		)
		(property "Public" "False"
			(at 10.09 292.81 0)
			(layer "B.Fab")
			(hide yes)
			(effects
				(font
					(size 1 1)
					(thickness 0.15)
				)
				(justify mirror)
			)
		)
		(property "Val" "100n"
			(at 10.09 292.81 0)
			(layer "B.Fab")
			(hide yes)
			(effects
				(font
					(size 1 1)
					(thickness 0.15)
				)
				(justify mirror)
			)
		)
		(property "Voltage" "50V"
			(at 10.09 292.81 0)
			(layer "B.Fab")
			(hide yes)
			(effects
				(font
					(size 1 1)
					(thickness 0.15)
				)
				(justify mirror)
			)
		)
		(sheetname "KR to SFI #1")
		(sheetfile "kr_sfi.kicad_sch")
		(attr smd)
		(fp_rect
			(start -0.925 0.47)
			(end 0.925 -0.47)
			(stroke
				(width 0.05)
				(type default)
			)
			(fill no)
			(layer "B.CrtYd")
		)
		(fp_line
			(start -0.494 0.25)
			(end -0.494 -0.248)
			(stroke
				(width 0.15)
				(type solid)
			)
			(layer "B.Fab")
		)
		(fp_line
			(start 0.504 0.25)
			(end -0.494 0.25)
			(stroke
				(width 0.15)
				(type solid)
			)
			(layer "B.Fab")
		)
		(fp_line
			(start -0.494 -0.248)
			(end 0.504 -0.248)
			(stroke
				(width 0.15)
				(type solid)
			)
			(layer "B.Fab")
		)
		(fp_line
			(start 0.504 -0.248)
			(end 0.504 0.25)
			(stroke
				(width 0.15)
				(type solid)
			)
			(layer "B.Fab")
		)
		(pad "1" smd roundrect
			(at -0.48 0 270)
			(size 0.59 0.64)
			(layers "B.Cu" "B.Mask" "B.Paste")
			(roundrect_rratio 0.25)
			(net 1 "GND")
			(pintype "passive")
			(teardrops
				(best_length_ratio 0.2)
				(max_length 1)
				(best_width_ratio 0.9)
				(max_width 2)
				(curved_edges yes)
				(filter_ratio 0.9)
				(enabled yes)
				(allow_two_segments yes)
				(prefer_zone_connections yes)
			)
		)
		(pad "2" smd roundrect
			(at 0.48 0 270)
			(size 0.59 0.64)
			(layers "B.Cu" "B.Mask" "B.Paste")
			(roundrect_rratio 0.25)
			(net 74 "+1V0")
			(pintype "passive")
			(teardrops
				(best_length_ratio 0.2)
				(max_length 1)
				(best_width_ratio 0.9)
				(max_width 2)
				(curved_edges yes)
				(filter_ratio 0.9)
				(enabled yes)
				(allow_two_segments yes)
				(prefer_zone_connections yes)
			)
		)
	)
	(footprint "antmicro-footprints:C_0402_1005Metric"
		(layer "B.Cu")
		(at 146.95 137.86)
		(descr "Capacitor SMD 0402")
		(tags "capacitor SMD 0402")
		(property "Reference" "C160"
			(at -1.5 1.35 0)
			(layer "B.SilkS")
			(effects
				(font
					(size 0.7 0.7)
					(thickness 0.15)
				)
				(justify right bottom mirror)
			)
		)
		(property "Value" "C_100n_0402"
			(at -1.022927 -2.155213 0)
			(layer "B.Fab")
			(effects
				(font
					(size 0.7 0.7)
					(thickness 0.15)
				)
				(justify right bottom mirror)
			)
		)
		(property "Datasheet" "https://www.murata.com/products/productdetail?partno=GRM155R61H104KE14%23"
			(at 0 0 0)
			(layer "F.Fab")
			(hide yes)
			(effects
				(font
					(size 1.27 1.27)
					(thickness 0.15)
				)
			)
		)
		(property "Author" "Antmicro"
			(at 0 0 0)
			(layer "B.Fab")
			(hide yes)
			(effects
				(font
					(size 1 1)
					(thickness 0.15)
				)
				(justify mirror)
			)
		)
		(property "Dielectric" "X5R"
			(at 0 0 0)
			(layer "B.Fab")
			(hide yes)
			(effects
				(font
					(size 1 1)
					(thickness 0.15)
				)
				(justify mirror)
			)
		)
		(property "License" "Apache-2.0"
			(at 0 0 0)
			(layer "B.Fab")
			(hide yes)
			(effects
				(font
					(size 1 1)
					(thickness 0.15)
				)
				(justify mirror)
			)
		)
		(property "MPN" "GRM155R61H104KE14D"
			(at 0 0 0)
			(layer "B.Fab")
			(hide yes)
			(effects
				(font
					(size 1 1)
					(thickness 0.15)
				)
				(justify mirror)
			)
		)
		(property "Manufacturer" "Murata"
			(at 0 0 0)
			(layer "B.Fab")
			(hide yes)
			(effects
				(font
					(size 1 1)
					(thickness 0.15)
				)
				(justify mirror)
			)
		)
		(property "Public" "False"
			(at 0 0 0)
			(layer "B.Fab")
			(hide yes)
			(effects
				(font
					(size 1 1)
					(thickness 0.15)
				)
				(justify mirror)
			)
		)
		(property "Val" "100n"
			(at 0 0 0)
			(layer "B.Fab")
			(hide yes)
			(effects
				(font
					(size 1 1)
					(thickness 0.15)
				)
				(justify mirror)
			)
		)
		(property "Voltage" "50V"
			(at 0 0 0)
			(layer "B.Fab")
			(hide yes)
			(effects
				(font
					(size 1 1)
					(thickness 0.15)
				)
				(justify mirror)
			)
		)
		(sheetname "KR to SFI #1")
		(sheetfile "kr_sfi.kicad_sch")
		(attr smd)
		(fp_rect
			(start -0.925 0.47)
			(end 0.925 -0.47)
			(stroke
				(width 0.05)
				(type default)
			)
			(fill no)
			(layer "B.CrtYd")
		)
		(fp_line
			(start -0.494 -0.248)
			(end 0.504 -0.248)
			(stroke
				(width 0.15)
				(type solid)
			)
			(layer "B.Fab")
		)
		(fp_line
			(start -0.494 0.25)
			(end -0.494 -0.248)
			(stroke
				(width 0.15)
				(type solid)
			)
			(layer "B.Fab")
		)
		(fp_line
			(start 0.504 -0.248)
			(end 0.504 0.25)
			(stroke
				(width 0.15)
				(type solid)
			)
			(layer "B.Fab")
		)
		(fp_line
			(start 0.504 0.25)
			(end -0.494 0.25)
			(stroke
				(width 0.15)
				(type solid)
			)
			(layer "B.Fab")
		)
		(pad "1" smd roundrect
			(at -0.48 0)
			(size 0.59 0.64)
			(layers "B.Cu" "B.Mask" "B.Paste")
			(roundrect_rratio 0.25)
			(net 1 "GND")
			(pintype "passive")
			(teardrops
				(best_length_ratio 0.2)
				(max_length 1)
				(best_width_ratio 0.9)
				(max_width 2)
				(curved_edges yes)
				(filter_ratio 0.9)
				(enabled yes)
				(allow_two_segments yes)
				(prefer_zone_connections yes)
			)
		)
		(pad "2" smd roundrect
			(at 0.48 0)
			(size 0.59 0.64)
			(layers "B.Cu" "B.Mask" "B.Paste")
			(roundrect_rratio 0.25)
			(net 74 "+1V0")
			(pintype "passive")
			(teardrops
				(best_length_ratio 0.2)
				(max_length 1)
				(best_width_ratio 0.9)
				(max_width 2)
				(curved_edges yes)
				(filter_ratio 0.9)
				(enabled yes)
				(allow_two_segments yes)
				(prefer_zone_connections yes)
			)
		)
	)
)
